(kicad_pcb
	(version 20241229)
	(generator "pcbnew")
	(generator_version "9.0")
	(general
		(thickness 1.6296)
		(legacy_teardrops no)
	)
	(paper "A3")
	(title_block
		(title "Thunderbolt to 10GbE adapter")
		(date "2026-04-21")
		(rev "1.1.0")
		(company "Antmicro Ltd")
		(comment 1 "www.antmicro.com")
		(comment 9 "footprints 192-195 of 703")
	)
	(layers
		(0 "F.Cu" signal)
		(4 "In1.Cu" signal)
		(6 "In2.Cu" signal)
		(8 "In3.Cu" signal)
		(10 "In4.Cu" signal)
		(12 "In5.Cu" signal)
		(14 "In6.Cu" signal)
		(2 "B.Cu" signal)
		(9 "F.Adhes" user "F.Adhesive")
		(11 "B.Adhes" user "B.Adhesive")
		(13 "F.Paste" user)
		(15 "B.Paste" user)
		(5 "F.SilkS" user "F.Silkscreen")
		(7 "B.SilkS" user "B.Silkscreen")
		(1 "F.Mask" user)
		(3 "B.Mask" user)
		(17 "Dwgs.User" user "User.Drawings")
		(19 "Cmts.User" user "User.Comments")
		(21 "Eco1.User" user "User.Eco1")
		(23 "Eco2.User" user "User.Eco2")
		(25 "Edge.Cuts" user)
		(27 "Margin" user)
		(31 "F.CrtYd" user "F.Courtyard")
		(29 "B.CrtYd" user "B.Courtyard")
		(35 "F.Fab" user)
		(33 "B.Fab" user)
	)
	(footprint "antmicro-footprints:SOT-753"
		(layer "F.Cu")
		(at 137.355 85.174999)
		(property "Reference" "U15"
			(at -0.555 -1.974999 0)
			(layer "F.SilkS")
			(effects
				(font
					(size 0.7 0.7)
					(thickness 0.15)
				)
				(justify left bottom)
			)
		)
		(property "Value" "74LVC1G07_SOT-753"
			(at 0 2.9 0)
			(layer "F.Fab")
			(effects
				(font
					(size 0.7 0.7)
					(thickness 0.15)
				)
				(justify left bottom)
			)
		)
		(property "Datasheet" "https://www.mouser.com/datasheet/2/916/74LVC1G07-1529858.pdf"
			(at 0 0 0)
			(layer "F.Fab")
			(hide yes)
			(effects
				(font
					(size 1.27 1.27)
					(thickness 0.15)
				)
			)
		)
		(property "Description" "Buffer, 74LVC1G07, 1.65 V to 5.5 V, SC-74A-5"
			(at 0 0 0)
			(layer "F.Fab")
			(hide yes)
			(effects
				(font
					(size 1.27 1.27)
					(thickness 0.15)
				)
			)
		)
		(property "MPN" "74LVC1G07GV,125"
			(at 0 0 0)
			(unlocked yes)
			(layer "F.Fab")
			(hide yes)
			(effects
				(font
					(size 1 1)
					(thickness 0.15)
				)
			)
		)
		(property "Manufacturer" "Nexperia"
			(at 0 0 0)
			(unlocked yes)
			(layer "F.Fab")
			(hide yes)
			(effects
				(font
					(size 1 1)
					(thickness 0.15)
				)
			)
		)
		(property "Author" "Antmicro"
			(at 0 0 0)
			(unlocked yes)
			(layer "F.Fab")
			(hide yes)
			(effects
				(font
					(size 1 1)
					(thickness 0.15)
				)
			)
		)
		(property "License" "Apache-2.0"
			(at 0 0 0)
			(unlocked yes)
			(layer "F.Fab")
			(hide yes)
			(effects
				(font
					(size 1 1)
					(thickness 0.15)
				)
			)
		)
		(sheetname "/X710-AT2 Misc/")
		(sheetfile "x710-at2-mics.kicad_sch")
		(attr smd)
		(fp_line
			(start -1.651 -1)
			(end -1.651 -0.701)
			(stroke
				(width 0.15)
				(type solid)
			)
			(layer "F.SilkS")
		)
		(fp_line
			(start -1.648 1)
			(end -1.648 0.677)
			(stroke
				(width 0.15)
				(type solid)
			)
			(layer "F.SilkS")
		)
		(fp_line
			(start -1.5 -1)
			(end -1.651 -1)
			(stroke
				(width 0.15)
				(type solid)
			)
			(layer "F.SilkS")
		)
		(fp_line
			(start -1.5 1)
			(end -1.648 1)
			(stroke
				(width 0.15)
				(type solid)
			)
			(layer "F.SilkS")
		)
		(fp_line
			(start 1.5 -1)
			(end 1.648 -1)
			(stroke
				(width 0.15)
				(type solid)
			)
			(layer "F.SilkS")
		)
		(fp_line
			(start 1.5 0.998)
			(end 1.648 0.998)
			(stroke
				(width 0.15)
				(type solid)
			)
			(layer "F.SilkS")
		)
		(fp_line
			(start 1.648 -1)
			(end 1.648 -0.677)
			(stroke
				(width 0.15)
				(type solid)
			)
			(layer "F.SilkS")
		)
		(fp_line
			(start 1.648 0.998)
			(end 1.648 0.699)
			(stroke
				(width 0.15)
				(type solid)
			)
			(layer "F.SilkS")
		)
		(fp_circle
			(center -1.5 1.35)
			(end -1.46 1.4)
			(stroke
				(width 0.15)
				(type solid)
			)
			(fill yes)
			(layer "F.SilkS")
		)
		(fp_rect
			(start -1.7 -1.901)
			(end 1.699 1.898)
			(stroke
				(width 0.05)
				(type solid)
			)
			(fill no)
			(layer "F.CrtYd")
		)
		(fp_line
			(start -1.526 -0.875)
			(end 1.523 -0.875)
			(stroke
				(width 0.15)
				(type solid)
			)
			(layer "F.Fab")
		)
		(fp_line
			(start -1.526 0.623)
			(end -1.526 -0.875)
			(stroke
				(width 0.15)
				(type solid)
			)
			(layer "F.Fab")
		)
		(fp_line
			(start -1.526 0.623)
			(end -1.351 0.873)
			(stroke
				(width 0.15)
				(type solid)
			)
			(layer "F.Fab")
		)
		(fp_line
			(start -1.351 0.873)
			(end 1.523 0.873)
			(stroke
				(width 0.15)
				(type solid)
			)
			(layer "F.Fab")
		)
		(fp_line
			(start 1.523 -0.875)
			(end 1.523 0.873)
			(stroke
				(width 0.15)
				(type solid)
			)
			(layer "F.Fab")
		)
		(fp_text user "Author: Antmicro"
			(at -1.651 7.225 0)
			(layer "F.Fab")
			(effects
				(font
					(size 0.7 0.7)
					(thickness 0.15)
				)
				(justify left bottom)
			)
		)
		(fp_text user "License: Apache-2.0"
			(at -1.651 8.425 0)
			(layer "F.Fab")
			(effects
				(font
					(size 0.7 0.7)
					(thickness 0.15)
				)
				(justify left bottom)
			)
		)
		(fp_text user "${REFERENCE}"
			(at -1.651 6.025 0)
			(layer "F.Fab")
			(effects
				(font
					(size 0.7 0.7)
					(thickness 0.15)
				)
				(justify left bottom)
			)
		)
		(pad "1" smd roundrect
			(at -0.951 1.35)
			(size 0.6 1.05)
			(layers "F.Cu" "F.Mask" "F.Paste")
			(roundrect_rratio 0.25)
			(net 588 "unconnected-(U15-NC-Pad1)")
			(pinfunction "NC")
			(pintype "no_connect")
		)
		(pad "2" smd roundrect
			(at 0 1.35)
			(size 0.6 1.05)
			(layers "F.Cu" "F.Mask" "F.Paste")
			(roundrect_rratio 0.25)
			(net 437 "Net-(U15-A)")
			(pinfunction "A")
			(pintype "input")
		)
		(pad "3" smd roundrect
			(at 0.949 1.35)
			(size 0.6 1.05)
			(layers "F.Cu" "F.Mask" "F.Paste")
			(roundrect_rratio 0.25)
			(net 23 "GND")
			(pinfunction "GND")
			(pintype "power_in")
		)
		(pad "4" smd roundrect
			(at 0.949 -1.351)
			(size 0.6 1.05)
			(layers "F.Cu" "F.Mask" "F.Paste")
			(roundrect_rratio 0.25)
			(net 74 "/X710-AT2 Misc/LAN_PWR_GOOD")
			(pinfunction "Y")
			(pintype "output")
		)
		(pad "5" smd roundrect
			(at -0.951 -1.351)
			(size 0.6 1.05)
			(layers "F.Cu" "F.Mask" "F.Paste")
			(roundrect_rratio 0.25)
			(net 7 "+3V3")
			(pinfunction "VCC")
			(pintype "power_in")
		)
	)
	(footprint "antmicro-footprints:R_0402_1005Metric"
		(layer "F.Cu")
		(at 130.4 145.5)
		(descr "Resistor SMD 0402")
		(tags "resistor SMD 0402")
		(property "Reference" "R237"
			(at 1 0.5 0)
			(layer "F.SilkS")
			(effects
				(font
					(size 0.7 0.7)
					(thickness 0.15)
				)
				(justify left bottom)
			)
		)
		(property "Value" "R_470R_0402"
			(at -1.011843 1.772047 0)
			(layer "F.Fab")
			(effects
				(font
					(size 0.7 0.7)
					(thickness 0.15)
				)
				(justify left bottom)
			)
		)
		(property "Datasheet" "https://www.bourns.com/docs/product-datasheets/cr.pdf"
			(at 0 0 0)
			(layer "F.Fab")
			(hide yes)
			(effects
				(font
					(size 1.27 1.27)
					(thickness 0.15)
				)
			)
		)
		(property "Description" "SMD Chip Resistor, 470 ohm, ± 1%, 62.5 mW, 0402 [1005 Metric], Thick Film, General Purpose"
			(at 0 0 0)
			(layer "F.Fab")
			(hide yes)
			(effects
				(font
					(size 1.27 1.27)
					(thickness 0.15)
				)
			)
		)
		(property "MPN" "CR0402-FX-4700GLF"
			(at 0 0 0)
			(unlocked yes)
			(layer "F.Fab")
			(hide yes)
			(effects
				(font
					(size 1 1)
					(thickness 0.15)
				)
			)
		)
		(property "Manufacturer" "Bourns"
			(at 0 0 0)
			(unlocked yes)
			(layer "F.Fab")
			(hide yes)
			(effects
				(font
					(size 1 1)
					(thickness 0.15)
				)
			)
		)
		(property "License" "Apache-2.0"
			(at 0 0 0)
			(unlocked yes)
			(layer "F.Fab")
			(hide yes)
			(effects
				(font
					(size 1 1)
					(thickness 0.15)
				)
			)
		)
		(property "Author" "Antmicro"
			(at 0 0 0)
			(unlocked yes)
			(layer "F.Fab")
			(hide yes)
			(effects
				(font
					(size 1 1)
					(thickness 0.15)
				)
			)
		)
		(property "Val" "470R"
			(at 0 0 0)
			(unlocked yes)
			(layer "F.Fab")
			(hide yes)
			(effects
				(font
					(size 1 1)
					(thickness 0.15)
				)
			)
		)
		(property "Tolerance" "1%"
			(at 0 0 0)
			(unlocked yes)
			(layer "F.Fab")
			(hide yes)
			(effects
				(font
					(size 1 1)
					(thickness 0.15)
				)
			)
		)
		(sheetname "/Power input/")
		(sheetfile "power_input.kicad_sch")
		(attr smd)
		(fp_rect
			(start -0.925 -0.47)
			(end 0.925 0.47)
			(stroke
				(width 0.05)
				(type default)
			)
			(fill no)
			(layer "F.CrtYd")
		)
		(fp_rect
			(start -0.5 -0.25)
			(end 0.5 0.25)
			(stroke
				(width 0.15)
				(type solid)
			)
			(fill no)
			(layer "F.Fab")
		)
		(fp_text user "${REFERENCE}"
			(at -0.95 3.168 0)
			(layer "F.Fab")
			(effects
				(font
					(size 0.7 0.7)
					(thickness 0.15)
				)
				(justify left bottom)
			)
		)
		(fp_text user "License: Apache-2.0"
			(at -0.95 5.169 0)
			(layer "F.Fab")
			(effects
				(font
					(size 0.7 0.7)
					(thickness 0.15)
				)
				(justify left bottom)
			)
		)
		(fp_text user "Author: Antmicro"
			(at -0.95 4.169 0)
			(layer "F.Fab")
			(effects
				(font
					(size 0.7 0.7)
					(thickness 0.15)
				)
				(justify left bottom)
			)
		)
		(pad "1" smd roundrect
			(at -0.48 0)
			(size 0.59 0.64)
			(layers "F.Cu" "F.Mask" "F.Paste")
			(roundrect_rratio 0.25)
			(net 421 "Net-(D18-A)")
			(pintype "passive")
		)
		(pad "2" smd roundrect
			(at 0.48 0)
			(size 0.59 0.64)
			(layers "F.Cu" "F.Mask" "F.Paste")
			(roundrect_rratio 0.25)
			(net 40 "+5V")
			(pintype "passive")
		)
	)
	(footprint "antmicro-footprints:C_0402_1005Metric"
		(layer "F.Cu")
		(at 161.4 49.5 -90)
		(descr "Capacitor SMD 0402")
		(tags "capacitor SMD 0402")
		(property "Reference" "C315"
			(at 0.9 -1.8 270)
			(layer "F.SilkS")
			(effects
				(font
					(size 0.7 0.7)
					(thickness 0.15)
				)
				(justify left bottom)
			)
		)
		(property "Value" "C_1u_0402"
			(at -1.022927 2.155213 270)
			(layer "F.Fab")
			(effects
				(font
					(size 0.7 0.7)
					(thickness 0.15)
				)
				(justify left bottom)
			)
		)
		(property "Datasheet" "https://product.tdk.com/en/search/capacitor/ceramic/mlcc/info?part_no=C1005X6S1A105K050BC"
			(at 0 0 270)
			(layer "F.Fab")
			(hide yes)
			(effects
				(font
					(size 1.27 1.27)
					(thickness 0.15)
				)
			)
		)
		(property "Description" "SMD Multilayer Ceramic Capacitor, 1 µF, 10 V, 0402 [1005 Metric], ± 10%, X6S, C"
			(at 0 0 270)
			(layer "F.Fab")
			(hide yes)
			(effects
				(font
					(size 1.27 1.27)
					(thickness 0.15)
				)
			)
		)
		(property "Manufacturer" "TDK"
			(at 0 0 270)
			(unlocked yes)
			(layer "F.Fab")
			(hide yes)
			(effects
				(font
					(size 1 1)
					(thickness 0.15)
				)
			)
		)
		(property "MPN" "C1005X6S1A105K050BC"
			(at 0 0 270)
			(unlocked yes)
			(layer "F.Fab")
			(hide yes)
			(effects
				(font
					(size 1 1)
					(thickness 0.15)
				)
			)
		)
		(property "Val" "1u"
			(at 0 0 270)
			(unlocked yes)
			(layer "F.Fab")
			(hide yes)
			(effects
				(font
					(size 1 1)
					(thickness 0.15)
				)
			)
		)
		(property "License" "Apache-2.0"
			(at 0 0 270)
			(unlocked yes)
			(layer "F.Fab")
			(hide yes)
			(effects
				(font
					(size 1 1)
					(thickness 0.15)
				)
			)
		)
		(property "Author" "Antmicro"
			(at 0 0 270)
			(unlocked yes)
			(layer "F.Fab")
			(hide yes)
			(effects
				(font
					(size 1 1)
					(thickness 0.15)
				)
			)
		)
		(property "Voltage" ""
			(at 0 0 270)
			(unlocked yes)
			(layer "F.Fab")
			(hide yes)
			(effects
				(font
					(size 1 1)
					(thickness 0.15)
				)
			)
		)
		(property "Dielectric" ""
			(at 0 0 270)
			(unlocked yes)
			(layer "F.Fab")
			(hide yes)
			(effects
				(font
					(size 1 1)
					(thickness 0.15)
				)
			)
		)
		(sheetname "/Power input/")
		(sheetfile "power_input.kicad_sch")
		(attr smd)
		(fp_rect
			(start -0.925 -0.47)
			(end 0.925 0.47)
			(stroke
				(width 0.05)
				(type default)
			)
			(fill no)
			(layer "F.CrtYd")
		)
		(fp_line
			(start -0.494 0.248)
			(end -0.494 -0.25)
			(stroke
				(width 0.15)
				(type solid)
			)
			(layer "F.Fab")
		)
		(fp_line
			(start 0.504 0.248)
			(end -0.494 0.248)
			(stroke
				(width 0.15)
				(type solid)
			)
			(layer "F.Fab")
		)
		(fp_line
			(start -0.494 -0.25)
			(end 0.504 -0.25)
			(stroke
				(width 0.15)
				(type solid)
			)
			(layer "F.Fab")
		)
		(fp_line
			(start 0.504 -0.25)
			(end 0.504 0.248)
			(stroke
				(width 0.15)
				(type solid)
			)
			(layer "F.Fab")
		)
		(fp_text user "${REFERENCE}"
			(at -0.939 4.599 270)
			(layer "F.Fab")
			(effects
				(font
					(size 0.7 0.7)
					(thickness 0.15)
				)
				(justify left bottom)
			)
		)
		(fp_text user "License: Apache-2.0"
			(at -0.939 5.799 270)
			(layer "F.Fab")
			(effects
				(font
					(size 0.7 0.7)
					(thickness 0.15)
				)
				(justify left bottom)
			)
		)
		(fp_text user "Author: Antmicro"
			(at -0.939 3.399 270)
			(layer "F.Fab")
			(effects
				(font
					(size 0.7 0.7)
					(thickness 0.15)
				)
				(justify left bottom)
			)
		)
		(pad "1" smd roundrect
			(at -0.48 0 270)
			(size 0.59 0.64)
			(layers "F.Cu" "F.Mask" "F.Paste")
			(roundrect_rratio 0.25)
			(net 23 "GND")
			(pintype "passive")
		)
		(pad "2" smd roundrect
			(at 0.48 0 270)
			(size 0.59 0.64)
			(layers "F.Cu" "F.Mask" "F.Paste")
			(roundrect_rratio 0.25)
			(net 345 "/Power input/5V_VDD")
			(pintype "passive")
		)
	)
	(footprint "antmicro-footprints:L_Bourns-SRP4021HMT"
		(layer "F.Cu")
		(at 139.45 106.000001 -90)
		(property "Reference" "L5"
			(at 17.549996 -16 270)
			(layer "F.SilkS")
			(effects
				(font
					(size 0.7 0.7)
					(thickness 0.15)
				)
			)
		)
		(property "Value" "L_1u_10A_Bourns-SRP4021HMT"
			(at -2.85 3.4 270)
			(layer "F.Fab")
			(effects
				(font
					(size 0.7 0.7)
					(thickness 0.15)
				)
				(justify left bottom)
			)
		)
		(property "Datasheet" "https://www.mouser.com/datasheet/2/54/Bourns_04_01_2025_SRP4021HMT_Datasheet-3580094.pdf"
			(at 0 0 270)
			(layer "F.Fab")
			(effects
				(font
					(size 0.7 0.7)
					(thickness 0.15)
				)
				(justify left bottom)
			)
		)
		(property "Description" "Power Inductors - SMD Ind,4.1x4.2x1.9mm,1uH+/-20%,10A, Shielded"
			(at 0 0 270)
			(layer "F.Fab")
			(effects
				(font
					(size 0.7 0.7)
					(thickness 0.15)
				)
				(justify left bottom)
			)
		)
		(property "Val" "1u/10A"
			(at 0 0 270)
			(unlocked yes)
			(layer "F.Fab")
			(hide yes)
			(effects
				(font
					(size 1 1)
					(thickness 0.15)
				)
			)
		)
		(property "Manufacturer" "Bourns"
			(at 0 0 270)
			(unlocked yes)
			(layer "F.Fab")
			(hide yes)
			(effects
				(font
					(size 1 1)
					(thickness 0.15)
				)
			)
		)
		(property "MPN" "SRP4021HMT-1R0M"
			(at 0 0 270)
			(unlocked yes)
			(layer "F.Fab")
			(hide yes)
			(effects
				(font
					(size 1 1)
					(thickness 0.15)
				)
			)
		)
		(property "ISat" ""
			(at 0 0 270)
			(unlocked yes)
			(layer "F.Fab")
			(hide yes)
			(effects
				(font
					(size 1 1)
					(thickness 0.15)
				)
			)
		)
		(property "Isat" "8A"
			(at 0 0 270)
			(unlocked yes)
			(layer "F.Fab")
			(hide yes)
			(effects
				(font
					(size 1 1)
					(thickness 0.15)
				)
			)
		)
		(property "IMax" ""
			(at 0 0 270)
			(unlocked yes)
			(layer "F.Fab")
			(hide yes)
			(effects
				(font
					(size 1 1)
					(thickness 0.15)
				)
			)
		)
		(property "Imax" "10A"
			(at 0 0 270)
			(unlocked yes)
			(layer "F.Fab")
			(hide yes)
			(effects
				(font
					(size 1 1)
					(thickness 0.15)
				)
			)
		)
		(property "Size" "4.2x4.1"
			(at 0 0 270)
			(unlocked yes)
			(layer "F.Fab")
			(hide yes)
			(effects
				(font
					(size 1 1)
					(thickness 0.15)
				)
			)
		)
		(property "Author" "Antmicro"
			(at 0 0 270)
			(unlocked yes)
			(layer "F.Fab")
			(hide yes)
			(effects
				(font
					(size 1 1)
					(thickness 0.15)
				)
			)
		)
		(property "License" "Apache-2.0"
			(at 0 0 270)
			(unlocked yes)
			(layer "F.Fab")
			(hide yes)
			(effects
				(font
					(size 1 1)
					(thickness 0.15)
				)
			)
		)
		(sheetname "/X710 DCDC converters/")
		(sheetfile "DCDC_converters_X710.kicad_sch")
		(attr smd)
		(fp_line
			(start -0.8 2.05)
			(end 0.8 2.05)
			(stroke
				(width 0.15)
				(type solid)
			)
			(layer "F.SilkS")
		)
		(fp_line
			(start -0.8 -2.05)
			(end 0.8 -2.05)
			(stroke
				(width 0.15)
				(type solid)
			)
			(layer "F.SilkS")
		)
		(fp_rect
			(start -2.85 -2.3)
			(end 2.85 2.3)
			(stroke
				(width 0.05)
				(type solid)
			)
			(fill no)
			(layer "F.CrtYd")
		)
		(fp_rect
			(start -2 -2.05)
			(end 2 2.05)
			(stroke
				(width 0.15)
				(type solid)
			)
			(fill no)
			(layer "F.Fab")
		)
		(fp_text user "License: Apache-2.0"
			(at -2.85 7 270)
			(layer "F.Fab")
			(effects
				(font
					(size 0.7 0.7)
					(thickness 0.15)
				)
				(justify left bottom)
			)
		)
		(fp_text user "${REFERENCE}"
			(at -2.85 5.8 270)
			(layer "F.Fab")
			(effects
				(font
					(size 0.7 0.7)
					(thickness 0.15)
				)
				(justify left bottom)
			)
		)
		(fp_text user "Author: Antmicro"
			(at -2.85 4.6 270)
			(layer "F.Fab")
			(effects
				(font
					(size 0.7 0.7)
					(thickness 0.15)
				)
				(justify left bottom)
			)
		)
		(pad "1" smd rect
			(at 1.85 0 90)
			(size 1.5 3.5)
			(layers "F.Cu" "F.Mask" "F.Paste")
			(net 153 "/X710 DCDC converters/VCCD_SW")
			(pintype "passive")
		)
		(pad "2" smd rect
			(at -1.85 0 90)
			(size 1.5 3.5)
			(layers "F.Cu" "F.Mask" "F.Paste")
			(net 335 "/X710 DCDC converters/+VCCD_OUT")
			(pintype "passive")
		)
	)
)
